(kicad_pcb
	(version 20260206)
	(generator "pcbnew")
	(generator_version "10.0")
	(general
		(thickness 1.6)
		(legacy_teardrops no)
	)
	(paper "A4")
	(title_block
		(title "01162023_DA0F0TEBIF0_F0T_Expander_BD_F_brd_V02_OCP.brd")
		(comment 1 "Grand Teton / footprints 8604-8612 of 9728")
	)
	(layers
		(0 "F.Cu" signal "TOP")
		(4 "In1.Cu" signal "GND")
		(6 "In2.Cu" signal "VCC")
		(8 "In3.Cu" signal "VCC1")
		(10 "In4.Cu" signal "GND1")
		(12 "In5.Cu" signal "IN1")
		(14 "In6.Cu" signal "GND2")
		(16 "In7.Cu" signal "IN2")
		(18 "In8.Cu" signal "GND3")
		(20 "In9.Cu" signal "IN3")
		(22 "In10.Cu" signal "GND4")
		(24 "In11.Cu" signal "IN4")
		(26 "In12.Cu" signal "GND5")
		(28 "In13.Cu" signal "IN5")
		(30 "In14.Cu" signal "GND6")
		(32 "In15.Cu" signal "IN6")
		(34 "In16.Cu" signal "GND7")
		(2 "B.Cu" signal "BOTTOM")
		(9 "F.Adhes" user "F.Adhesive")
		(11 "B.Adhes" user "B.Adhesive")
		(13 "F.Paste" user "Package Geometry/Pastemask Top")
		(15 "B.Paste" user "Package Geometry/Pastemask Bottom")
		(5 "F.SilkS" user "Ref Des/Silkscreen Top")
		(7 "B.SilkS" user "Ref Des/Silkscreen Bottom")
		(1 "F.Mask" user "Board Geometry/Soldermask Top")
		(3 "B.Mask" user "Board Geometry/Soldermask Bottom")
		(17 "Dwgs.User" user "User.Drawings")
		(19 "Cmts.User" user "User.Comments")
		(21 "Eco1.User" user "User.Eco1")
		(23 "Eco2.User" user "User.Eco2")
		(25 "Edge.Cuts" user "Board Geometry/Outline")
		(27 "Margin" user)
		(31 "F.CrtYd" user "Package Geometry/Place Bound Top")
		(29 "B.CrtYd" user "Package Geometry/Place Bound Bottom")
		(35 "F.Fab" user "Ref Des/Assembly Top")
		(33 "B.Fab" user "Ref Des/Assembly Bottom")
	)
	(footprint ""
		(layer "B.Cu")
		(at 347.96603 -308.613556 90)
		(property "Reference" "C1669"
			(at 0 0 90)
			(layer "B.SilkS")
			(hide yes)
			(effects
				(font
					(size 1.27 1.27)
				)
				(justify mirror)
			)
		)
		(property "Value" ""
			(at 0 0 90)
			(layer "B.Fab")
			(effects
				(font
					(size 1.27 1.27)
				)
				(justify mirror)
			)
		)
		(duplicate_pad_numbers_are_jumpers no)
		(fp_line
			(start 1.2954 -0.5842)
			(end -1.2954 -0.5842)
			(stroke
				(width 0.1524)
				(type default)
			)
			(layer "B.SilkS")
		)
		(fp_line
			(start -1.2954 -0.5842)
			(end -1.2954 0.5842)
			(stroke
				(width 0.1524)
				(type default)
			)
			(layer "B.SilkS")
		)
		(fp_line
			(start 1.2954 0.5842)
			(end 1.2954 -0.5842)
			(stroke
				(width 0.1524)
				(type default)
			)
			(layer "B.SilkS")
		)
		(fp_line
			(start -1.2954 0.5842)
			(end 1.2954 0.5842)
			(stroke
				(width 0.1524)
				(type default)
			)
			(layer "B.SilkS")
		)
		(fp_line
			(start 0.8636 -0.4572)
			(end -0.8636 -0.4572)
			(stroke
				(width 0.1)
				(type default)
			)
			(layer "B.Fab")
		)
		(fp_line
			(start -0.8636 -0.4572)
			(end -0.8636 -0.4064)
			(stroke
				(width 0.1)
				(type default)
			)
			(layer "B.Fab")
		)
		(fp_line
			(start 1.1938 -0.4064)
			(end 0.8636 -0.4064)
			(stroke
				(width 0.1)
				(type default)
			)
			(layer "B.Fab")
		)
		(fp_line
			(start 0.8636 -0.4064)
			(end 0.8636 -0.4572)
			(stroke
				(width 0.1)
				(type default)
			)
			(layer "B.Fab")
		)
		(fp_line
			(start -0.8636 -0.4064)
			(end -1.1938 -0.4064)
			(stroke
				(width 0.1)
				(type default)
			)
			(layer "B.Fab")
		)
		(fp_line
			(start -1.1938 -0.4064)
			(end -1.1938 0.4064)
			(stroke
				(width 0.1)
				(type default)
			)
			(layer "B.Fab")
		)
		(fp_line
			(start 1.1938 0.4064)
			(end 1.1938 -0.4064)
			(stroke
				(width 0.1)
				(type default)
			)
			(layer "B.Fab")
		)
		(fp_line
			(start 0.8636 0.4064)
			(end 1.1938 0.4064)
			(stroke
				(width 0.1)
				(type default)
			)
			(layer "B.Fab")
		)
		(fp_line
			(start -0.8636 0.4064)
			(end -0.8636 0.4572)
			(stroke
				(width 0.1)
				(type default)
			)
			(layer "B.Fab")
		)
		(fp_line
			(start -1.1938 0.4064)
			(end -0.8636 0.4064)
			(stroke
				(width 0.1)
				(type default)
			)
			(layer "B.Fab")
		)
		(fp_line
			(start 0.8636 0.4572)
			(end 0.8636 0.4064)
			(stroke
				(width 0.1)
				(type default)
			)
			(layer "B.Fab")
		)
		(fp_line
			(start -0.8636 0.4572)
			(end 0.8636 0.4572)
			(stroke
				(width 0.1)
				(type default)
			)
			(layer "B.Fab")
		)
		(pad "1" smd rect
			(at 0.7366 0)
			(size 0.7112 0.8128)
			(layers "B.Cu" "B.Mask" "B.Paste")
			(net "P0V8_SERDES_VDDA_PEX2")
		)
		(pad "2" smd rect
			(at -0.7366 0)
			(size 0.7112 0.8128)
			(layers "B.Cu" "B.Mask" "B.Paste")
			(net "GND")
		)
	)
	(footprint ""
		(layer "B.Cu")
		(at 399.874994 -293.99992 -90)
		(property "Reference" "C1880"
			(at 0 0 90)
			(layer "B.SilkS")
			(hide yes)
			(effects
				(font
					(size 1.27 1.27)
				)
				(justify mirror)
			)
		)
		(property "Value" ""
			(at 0 0 90)
			(layer "B.Fab")
			(effects
				(font
					(size 1.27 1.27)
				)
				(justify mirror)
			)
		)
		(duplicate_pad_numbers_are_jumpers no)
		(fp_line
			(start -0.299974 0.150114)
			(end 0.299974 0.150114)
			(stroke
				(width 0.1)
				(type default)
			)
			(layer "B.Fab")
		)
		(fp_line
			(start 0.299974 0.150114)
			(end 0.299974 -0.150114)
			(stroke
				(width 0.1)
				(type default)
			)
			(layer "B.Fab")
		)
		(fp_line
			(start -0.299974 -0.150114)
			(end -0.299974 0.150114)
			(stroke
				(width 0.1)
				(type default)
			)
			(layer "B.Fab")
		)
		(fp_line
			(start 0.299974 -0.150114)
			(end -0.299974 -0.150114)
			(stroke
				(width 0.1)
				(type default)
			)
			(layer "B.Fab")
		)
		(pad "1" smd rect
			(at 0.2667 0 90)
			(size 0.3048 0.381)
			(layers "B.Cu" "B.Mask" "B.Paste")
			(net "P0V8_PEX3")
		)
		(pad "2" smd rect
			(at -0.2667 0 90)
			(size 0.3048 0.381)
			(layers "B.Cu" "B.Mask" "B.Paste")
			(net "GND")
		)
	)
	(footprint ""
		(layer "B.Cu")
		(at 359.23474 -303.649634 -90)
		(property "Reference" "PC182"
			(at 0 0 90)
			(layer "B.SilkS")
			(hide yes)
			(effects
				(font
					(size 1.27 1.27)
				)
				(justify mirror)
			)
		)
		(property "Value" ""
			(at 0 0 90)
			(layer "B.Fab")
			(effects
				(font
					(size 1.27 1.27)
				)
				(justify mirror)
			)
		)
		(duplicate_pad_numbers_are_jumpers no)
		(fp_line
			(start -1.524 0.762)
			(end 1.524 0.762)
			(stroke
				(width 0.1524)
				(type default)
			)
			(layer "B.SilkS")
		)
		(fp_line
			(start 1.524 0.762)
			(end 1.524 -0.762)
			(stroke
				(width 0.1524)
				(type default)
			)
			(layer "B.SilkS")
		)
		(fp_line
			(start -1.524 -0.762)
			(end -1.524 0.762)
			(stroke
				(width 0.1524)
				(type default)
			)
			(layer "B.SilkS")
		)
		(fp_line
			(start 1.524 -0.762)
			(end -1.524 -0.762)
			(stroke
				(width 0.1524)
				(type default)
			)
			(layer "B.SilkS")
		)
		(fp_line
			(start -1.1049 0.724916)
			(end -1.1049 -0.724916)
			(stroke
				(width 0.1)
				(type default)
			)
			(layer "B.Fab")
		)
		(fp_line
			(start 1.1049 0.724916)
			(end -1.1049 0.724916)
			(stroke
				(width 0.1)
				(type default)
			)
			(layer "B.Fab")
		)
		(fp_line
			(start -1.1049 -0.724916)
			(end 1.1049 -0.724916)
			(stroke
				(width 0.1)
				(type default)
			)
			(layer "B.Fab")
		)
		(fp_line
			(start 1.1049 -0.724916)
			(end 1.1049 0.724916)
			(stroke
				(width 0.1)
				(type default)
			)
			(layer "B.Fab")
		)
		(pad "1" smd rect
			(at 0.889 0 270)
			(size 1.016 1.27)
			(layers "B.Cu" "B.Mask" "B.Paste")
			(net "P0V8_PEX3")
		)
		(pad "2" smd rect
			(at -0.889 0 270)
			(size 1.016 1.27)
			(layers "B.Cu" "B.Mask" "B.Paste")
			(net "GND")
		)
	)
	(footprint ""
		(layer "B.Cu")
		(at 415.549842 -296.37482)
		(property "Reference" "C1936"
			(at 0 0 0)
			(layer "B.SilkS")
			(hide yes)
			(effects
				(font
					(size 1.27 1.27)
				)
				(justify mirror)
			)
		)
		(property "Value" ""
			(at 0 0 0)
			(layer "B.Fab")
			(effects
				(font
					(size 1.27 1.27)
				)
				(justify mirror)
			)
		)
		(duplicate_pad_numbers_are_jumpers no)
		(fp_line
			(start -0.299974 -0.150114)
			(end -0.299974 0.150114)
			(stroke
				(width 0.1)
				(type default)
			)
			(layer "B.Fab")
		)
		(fp_line
			(start -0.299974 0.150114)
			(end 0.299974 0.150114)
			(stroke
				(width 0.1)
				(type default)
			)
			(layer "B.Fab")
		)
		(fp_line
			(start 0.299974 -0.150114)
			(end -0.299974 -0.150114)
			(stroke
				(width 0.1)
				(type default)
			)
			(layer "B.Fab")
		)
		(fp_line
			(start 0.299974 0.150114)
			(end 0.299974 -0.150114)
			(stroke
				(width 0.1)
				(type default)
			)
			(layer "B.Fab")
		)
		(pad "1" smd rect
			(at 0.2667 0 180)
			(size 0.3048 0.381)
			(layers "B.Cu" "B.Mask" "B.Paste")
			(net "P0V8_SERDES_VDDA_PEX3")
		)
		(pad "2" smd rect
			(at -0.2667 0 180)
			(size 0.3048 0.381)
			(layers "B.Cu" "B.Mask" "B.Paste")
			(net "GND")
		)
	)
	(footprint ""
		(layer "B.Cu")
		(at 114.450114 -256.226564 -90)
		(property "Reference" "PR97"
			(at 0 0 90)
			(layer "B.SilkS")
			(hide yes)
			(effects
				(font
					(size 1.27 1.27)
				)
				(justify mirror)
			)
		)
		(property "Value" ""
			(at 0 0 90)
			(layer "B.Fab")
			(effects
				(font
					(size 1.27 1.27)
				)
				(justify mirror)
			)
		)
		(duplicate_pad_numbers_are_jumpers no)
		(fp_line
			(start -0.7874 0.4064)
			(end 0.7874 0.4064)
			(stroke
				(width 0.1524)
				(type default)
			)
			(layer "B.SilkS")
		)
		(fp_line
			(start 0.7874 0.4064)
			(end 0.7874 -0.4064)
			(stroke
				(width 0.1524)
				(type default)
			)
			(layer "B.SilkS")
		)
		(fp_line
			(start -0.7874 -0.4064)
			(end -0.7874 0.4064)
			(stroke
				(width 0.1524)
				(type default)
			)
			(layer "B.SilkS")
		)
		(fp_line
			(start 0.7874 -0.4064)
			(end -0.7874 -0.4064)
			(stroke
				(width 0.1524)
				(type default)
			)
			(layer "B.SilkS")
		)
		(fp_line
			(start -0.67945 0.3048)
			(end -0.120396 0.3048)
			(stroke
				(width 0.1)
				(type default)
			)
			(layer "B.Fab")
		)
		(fp_line
			(start -0.120396 0.3048)
			(end -0.120396 0.2794)
			(stroke
				(width 0.1)
				(type default)
			)
			(layer "B.Fab")
		)
		(fp_line
			(start 0.12065 0.3048)
			(end 0.67945 0.3048)
			(stroke
				(width 0.1)
				(type default)
			)
			(layer "B.Fab")
		)
		(fp_line
			(start 0.67945 0.3048)
			(end 0.67945 -0.305054)
			(stroke
				(width 0.1)
				(type default)
			)
			(layer "B.Fab")
		)
		(fp_line
			(start -0.120396 0.2794)
			(end 0.12065 0.2794)
			(stroke
				(width 0.1)
				(type default)
			)
			(layer "B.Fab")
		)
		(fp_line
			(start 0.12065 0.2794)
			(end 0.12065 0.3048)
			(stroke
				(width 0.1)
				(type default)
			)
			(layer "B.Fab")
		)
		(fp_line
			(start -0.12065 -0.2794)
			(end -0.12065 -0.3048)
			(stroke
				(width 0.1)
				(type default)
			)
			(layer "B.Fab")
		)
		(fp_line
			(start 0.12065 -0.2794)
			(end -0.12065 -0.2794)
			(stroke
				(width 0.1)
				(type default)
			)
			(layer "B.Fab")
		)
		(fp_line
			(start -0.67945 -0.3048)
			(end -0.67945 0.3048)
			(stroke
				(width 0.1)
				(type default)
			)
			(layer "B.Fab")
		)
		(fp_line
			(start -0.12065 -0.3048)
			(end -0.67945 -0.3048)
			(stroke
				(width 0.1)
				(type default)
			)
			(layer "B.Fab")
		)
		(fp_line
			(start 0.12065 -0.305054)
			(end 0.12065 -0.2794)
			(stroke
				(width 0.1)
				(type default)
			)
			(layer "B.Fab")
		)
		(fp_line
			(start 0.67945 -0.305054)
			(end 0.12065 -0.305054)
			(stroke
				(width 0.1)
				(type default)
			)
			(layer "B.Fab")
		)
		(pad "1" smd circle
			(at 0.40005 0 90)
			(size 0 0)
			(layers "B.Cu" "B.Mask" "B.Paste")
			(net "P12V_AUX")
		)
		(pad "2" smd circle
			(at -0.40005 0 90)
			(size 0 0)
			(layers "B.Cu" "B.Mask" "B.Paste")
			(net "P0V8_PEX0_VINSEN")
		)
	)
	(footprint ""
		(layer "B.Cu")
		(at 115.943888 -321.390518 -90)
		(property "Reference" "R6450"
			(at 0 0 90)
			(layer "B.SilkS")
			(hide yes)
			(effects
				(font
					(size 1.27 1.27)
				)
				(justify mirror)
			)
		)
		(property "Value" ""
			(at 0 0 90)
			(layer "B.Fab")
			(effects
				(font
					(size 1.27 1.27)
				)
				(justify mirror)
			)
		)
		(duplicate_pad_numbers_are_jumpers no)
		(fp_line
			(start -0.7874 0.4064)
			(end 0.7874 0.4064)
			(stroke
				(width 0.1524)
				(type default)
			)
			(layer "B.SilkS")
		)
		(fp_line
			(start 0.7874 0.4064)
			(end 0.7874 -0.4064)
			(stroke
				(width 0.1524)
				(type default)
			)
			(layer "B.SilkS")
		)
		(fp_line
			(start -0.7874 -0.4064)
			(end -0.7874 0.4064)
			(stroke
				(width 0.1524)
				(type default)
			)
			(layer "B.SilkS")
		)
		(fp_line
			(start 0.7874 -0.4064)
			(end -0.7874 -0.4064)
			(stroke
				(width 0.1524)
				(type default)
			)
			(layer "B.SilkS")
		)
		(fp_line
			(start -0.67945 0.3048)
			(end -0.120396 0.3048)
			(stroke
				(width 0.1)
				(type default)
			)
			(layer "B.Fab")
		)
		(fp_line
			(start -0.120396 0.3048)
			(end -0.120396 0.2794)
			(stroke
				(width 0.1)
				(type default)
			)
			(layer "B.Fab")
		)
		(fp_line
			(start 0.12065 0.3048)
			(end 0.67945 0.3048)
			(stroke
				(width 0.1)
				(type default)
			)
			(layer "B.Fab")
		)
		(fp_line
			(start 0.67945 0.3048)
			(end 0.67945 -0.305054)
			(stroke
				(width 0.1)
				(type default)
			)
			(layer "B.Fab")
		)
		(fp_line
			(start -0.120396 0.2794)
			(end 0.12065 0.2794)
			(stroke
				(width 0.1)
				(type default)
			)
			(layer "B.Fab")
		)
		(fp_line
			(start 0.12065 0.2794)
			(end 0.12065 0.3048)
			(stroke
				(width 0.1)
				(type default)
			)
			(layer "B.Fab")
		)
		(fp_line
			(start -0.12065 -0.2794)
			(end -0.12065 -0.3048)
			(stroke
				(width 0.1)
				(type default)
			)
			(layer "B.Fab")
		)
		(fp_line
			(start 0.12065 -0.2794)
			(end -0.12065 -0.2794)
			(stroke
				(width 0.1)
				(type default)
			)
			(layer "B.Fab")
		)
		(fp_line
			(start -0.67945 -0.3048)
			(end -0.67945 0.3048)
			(stroke
				(width 0.1)
				(type default)
			)
			(layer "B.Fab")
		)
		(fp_line
			(start -0.12065 -0.3048)
			(end -0.67945 -0.3048)
			(stroke
				(width 0.1)
				(type default)
			)
			(layer "B.Fab")
		)
		(fp_line
			(start 0.12065 -0.305054)
			(end 0.12065 -0.2794)
			(stroke
				(width 0.1)
				(type default)
			)
			(layer "B.Fab")
		)
		(fp_line
			(start 0.67945 -0.305054)
			(end 0.12065 -0.305054)
			(stroke
				(width 0.1)
				(type default)
			)
			(layer "B.Fab")
		)
		(pad "1" smd circle
			(at 0.40005 0 90)
			(size 0 0)
			(layers "B.Cu" "B.Mask" "B.Paste")
			(net "P0V8_SERDES_VDDA_PEX0")
		)
		(pad "2" smd circle
			(at -0.40005 0 90)
			(size 0 0)
			(layers "B.Cu" "B.Mask" "B.Paste")
			(net "P0V8_SERDES_VDDA_PEX0_C1")
		)
	)
	(footprint ""
		(layer "B.Cu")
		(at 279.974802 -294.132 -90)
		(property "Reference" "C3395"
			(at 0 0 90)
			(layer "B.SilkS")
			(hide yes)
			(effects
				(font
					(size 1.27 1.27)
				)
				(justify mirror)
			)
		)
		(property "Value" ""
			(at 0 0 90)
			(layer "B.Fab")
			(effects
				(font
					(size 1.27 1.27)
				)
				(justify mirror)
			)
		)
		(duplicate_pad_numbers_are_jumpers no)
		(fp_line
			(start -0.299974 0.150114)
			(end 0.299974 0.150114)
			(stroke
				(width 0.1)
				(type default)
			)
			(layer "B.Fab")
		)
		(fp_line
			(start 0.299974 0.150114)
			(end 0.299974 -0.150114)
			(stroke
				(width 0.1)
				(type default)
			)
			(layer "B.Fab")
		)
		(fp_line
			(start -0.299974 -0.150114)
			(end -0.299974 0.150114)
			(stroke
				(width 0.1)
				(type default)
			)
			(layer "B.Fab")
		)
		(fp_line
			(start 0.299974 -0.150114)
			(end -0.299974 -0.150114)
			(stroke
				(width 0.1)
				(type default)
			)
			(layer "B.Fab")
		)
		(pad "1" smd rect
			(at 0.2667 0 90)
			(size 0.3048 0.381)
			(layers "B.Cu" "B.Mask" "B.Paste")
			(net "PCEPLL5_VDDA18_PEX2")
		)
		(pad "2" smd rect
			(at -0.2667 0 90)
			(size 0.3048 0.381)
			(layers "B.Cu" "B.Mask" "B.Paste")
			(net "GND")
		)
	)
	(footprint ""
		(layer "B.Cu")
		(at 343.693242 -220.38691 90)
		(property "Reference" "C2071"
			(at 0 0 90)
			(layer "B.SilkS")
			(hide yes)
			(effects
				(font
					(size 1.27 1.27)
				)
				(justify mirror)
			)
		)
		(property "Value" ""
			(at 0 0 90)
			(layer "B.Fab")
			(effects
				(font
					(size 1.27 1.27)
				)
				(justify mirror)
			)
		)
		(duplicate_pad_numbers_are_jumpers no)
		(fp_line
			(start 0.69215 -0.2921)
			(end -0.69215 -0.2921)
			(stroke
				(width 0.1524)
				(type default)
			)
			(layer "B.SilkS")
		)
		(fp_line
			(start -0.69215 -0.2921)
			(end -0.69215 0.2921)
			(stroke
				(width 0.1524)
				(type default)
			)
			(layer "B.SilkS")
		)
		(fp_line
			(start 0.69215 0.2921)
			(end 0.69215 -0.2921)
			(stroke
				(width 0.1524)
				(type default)
			)
			(layer "B.SilkS")
		)
		(fp_line
			(start -0.69215 0.2921)
			(end 0.69215 0.2921)
			(stroke
				(width 0.1524)
				(type default)
			)
			(layer "B.SilkS")
		)
		(fp_line
			(start 0.51435 -0.2794)
			(end -0.51435 -0.2794)
			(stroke
				(width 0.1)
				(type default)
			)
			(layer "B.Fab")
		)
		(fp_line
			(start -0.51435 -0.2794)
			(end -0.51435 0.2794)
			(stroke
				(width 0.1)
				(type default)
			)
			(layer "B.Fab")
		)
		(fp_line
			(start 0.51435 0.2794)
			(end 0.51435 -0.2794)
			(stroke
				(width 0.1)
				(type default)
			)
			(layer "B.Fab")
		)
		(fp_line
			(start -0.51435 0.2794)
			(end 0.51435 0.2794)
			(stroke
				(width 0.1)
				(type default)
			)
			(layer "B.Fab")
		)
		(pad "1" smd circle
			(at 0.40005 0 270)
			(size 0 0)
			(layers "B.Cu" "B.Mask" "B.Paste")
			(net "P3V3_VCC_FPGA_CORE")
		)
		(pad "2" smd circle
			(at -0.40005 0 270)
			(size 0 0)
			(layers "B.Cu" "B.Mask" "B.Paste")
			(net "GND")
		)
		(zone
			(layer "B.Cu")
			(hatch none 0.5)
			(connect_pads
				(clearance 0)
			)
			(min_thickness 0.25)
			(keepout
				(tracks not_allowed)
				(vias allowed)
				(pads allowed)
				(copperpour not_allowed)
				(footprints allowed)
			)
			(placement
				(enabled no)
				(sheetname "")
			)
			(fill
				(thermal_gap 0.5)
				(thermal_bridge_width 0.5)
				(island_removal_mode 0)
			)
			(polygon
				(pts
					(xy 343.780872 -220.57741) (xy 343.839038 -220.48597) (xy 343.839038 -220.28658) (xy 343.780872 -220.19641)
					(xy 343.605612 -220.19641) (xy 343.547192 -220.28658) (xy 343.547192 -220.48597) (xy 343.605358 -220.57741)
				)
			)
		)
	)
	(footprint ""
		(layer "B.Cu")
		(at 104.41813 -281.024838 90)
		(property "Reference" "PC78"
			(at 0 0 90)
			(layer "B.SilkS")
			(hide yes)
			(effects
				(font
					(size 1.27 1.27)
				)
				(justify mirror)
			)
		)
		(property "Value" ""
			(at 0 0 90)
			(layer "B.Fab")
			(effects
				(font
					(size 1.27 1.27)
				)
				(justify mirror)
			)
		)
		(duplicate_pad_numbers_are_jumpers no)
		(fp_line
			(start 1.524 -0.762)
			(end -1.524 -0.762)
			(stroke
				(width 0.1524)
				(type default)
			)
			(layer "B.SilkS")
		)
		(fp_line
			(start -1.524 -0.762)
			(end -1.524 0.762)
			(stroke
				(width 0.1524)
				(type default)
			)
			(layer "B.SilkS")
		)
		(fp_line
			(start 1.524 0.762)
			(end 1.524 -0.762)
			(stroke
				(width 0.1524)
				(type default)
			)
			(layer "B.SilkS")
		)
		(fp_line
			(start -1.524 0.762)
			(end 1.524 0.762)
			(stroke
				(width 0.1524)
				(type default)
			)
			(layer "B.SilkS")
		)
		(fp_line
			(start 1.1049 -0.724916)
			(end 1.1049 0.724916)
			(stroke
				(width 0.1)
				(type default)
			)
			(layer "B.Fab")
		)
		(fp_line
			(start -1.1049 -0.724916)
			(end 1.1049 -0.724916)
			(stroke
				(width 0.1)
				(type default)
			)
			(layer "B.Fab")
		)
		(fp_line
			(start 1.1049 0.724916)
			(end -1.1049 0.724916)
			(stroke
				(width 0.1)
				(type default)
			)
			(layer "B.Fab")
		)
		(fp_line
			(start -1.1049 0.724916)
			(end -1.1049 -0.724916)
			(stroke
				(width 0.1)
				(type default)
			)
			(layer "B.Fab")
		)
		(pad "1" smd rect
			(at 0.889 0 90)
			(size 1.016 1.27)
			(layers "B.Cu" "B.Mask" "B.Paste")
			(net "SW_P12V_P0V8_PEX0_FLT")
		)
		(pad "2" smd rect
			(at -0.889 0 90)
			(size 1.016 1.27)
			(layers "B.Cu" "B.Mask" "B.Paste")
			(net "GND")
		)
	)
)
